# BASEBOARD_FAB2 (Tioga Pass) — schematic netlist excerpt (pin names and nets, part order shuffled) for the footprints in the layout excerpt that follows; sources: Cadence DE-HDL packaged netlist, KiCad conversion of Wiwynn_Tioga_Pass_MB.brd

R6W16  RES  1.00K 1% CHIP  pkg 0402  page 168 : A = P3V3_STBY ; B = FM_SOL_UART_CH_SEL
C9P17  CAP_A  0.1UF 16V 10% EMPTY  pkg 0402V  page 200 : A = A_HSC_MON ; B = AGND_HSC
C8P4  CAP  100UF 4V 20% X5R  pkg 0805  page 228 : A = PVDDQ_KLM ; B = GND

(kicad_pcb
	(version 20260206)
	(generator "pcbnew")
	(generator_version "10.0")
	(general
		(thickness 1.6)
		(legacy_teardrops no)
	)
	(paper "A4")
	(title_block
		(title "Wiwynn_Tioga_Pass_MB.brd")
		(comment 1 "Tioga Pass / footprints 4206-4208 of 4770")
	)
	(layers
		(0 "F.Cu" signal "TOP")
		(4 "In1.Cu" signal "L2GND")
		(6 "In2.Cu" signal "L3")
		(8 "In3.Cu" signal "L4GND")
		(10 "In4.Cu" signal "L5")
		(12 "In5.Cu" signal "L6GND")
		(14 "In6.Cu" signal "L7VCC")
		(16 "In7.Cu" signal "L8VCC")
		(18 "In8.Cu" signal "L9GND")
		(20 "In9.Cu" signal "L10")
		(22 "In10.Cu" signal "L11GND")
		(24 "In11.Cu" signal "L12")
		(26 "In12.Cu" signal "L13GND")
		(2 "B.Cu" signal "BOTTOM")
		(9 "F.Adhes" user "F.Adhesive")
		(11 "B.Adhes" user "B.Adhesive")
		(13 "F.Paste" user "Package Geometry/Pastemask Top")
		(15 "B.Paste" user "Package Geometry/Pastemask Bottom")
		(5 "F.SilkS" user "Ref Des/Silkscreen Top")
		(7 "B.SilkS" user "Ref Des/Silkscreen Bottom")
		(1 "F.Mask" user "Board Geometry/Soldermask Top")
		(3 "B.Mask" user "Board Geometry/Soldermask Bottom")
		(17 "Dwgs.User" user "User.Drawings")
		(19 "Cmts.User" user "User.Comments")
		(21 "Eco1.User" user "User.Eco1")
		(23 "Eco2.User" user "User.Eco2")
		(25 "Edge.Cuts" user "Board Geometry/Outline")
		(27 "Margin" user)
		(31 "F.CrtYd" user "Package Geometry/Place Bound Top")
		(29 "B.CrtYd" user "Package Geometry/Place Bound Bottom")
		(35 "F.Fab" user "Ref Des/Assembly Top")
		(33 "B.Fab" user "Ref Des/Assembly Bottom")
	)
	(footprint ""
		(layer "B.Cu")
		(at 17.526 -73.406 180)
		(property "Reference" "C9P17"
			(at 0 0 0)
			(layer "B.SilkS")
			(hide yes)
			(effects
				(font
					(size 1.27 1.27)
				)
				(justify mirror)
			)
		)
		(property "Value" ""
			(at 0 0 0)
			(layer "B.Fab")
			(effects
				(font
					(size 1.27 1.27)
				)
				(justify mirror)
			)
		)
		(duplicate_pad_numbers_are_jumpers no)
		(fp_rect
			(start -0.3048 0.9906)
			(end 0.3048 -0.1016)
			(stroke
				(width 0)
				(type default)
			)
			(fill no)
			(layer "B.CrtYd")
		)
		(fp_line
			(start 0.3048 0.9906)
			(end -0.3048 0.9906)
			(stroke
				(width 0.1)
				(type default)
			)
			(layer "B.Fab")
		)
		(fp_line
			(start 0.3048 -0.1016)
			(end 0.3048 0.9906)
			(stroke
				(width 0.1)
				(type default)
			)
			(layer "B.Fab")
		)
		(fp_line
			(start -0.3048 0.9906)
			(end -0.3048 -0.1016)
			(stroke
				(width 0.1)
				(type default)
			)
			(layer "B.Fab")
		)
		(fp_line
			(start -0.3048 -0.1016)
			(end 0.3048 -0.1016)
			(stroke
				(width 0.1)
				(type default)
			)
			(layer "B.Fab")
		)
		(pad "1" smd rect
			(at 0 0)
			(size 0.508 0.508)
			(layers "B.Cu" "B.Mask" "B.Paste")
			(net "A_HSC_MON")
		)
		(pad "2" smd rect
			(at 0 0.889)
			(size 0.508 0.508)
			(layers "B.Cu" "B.Mask" "B.Paste")
			(net "AGND_HSC")
		)
		(zone
			(layer "B.Cu")
			(hatch none 0.5)
			(connect_pads
				(clearance 0)
			)
			(min_thickness 0.25)
			(keepout
				(tracks not_allowed)
				(vias allowed)
				(pads allowed)
				(copperpour not_allowed)
				(footprints allowed)
			)
			(placement
				(enabled no)
				(sheetname "")
			)
			(fill
				(thermal_gap 0.5)
				(thermal_bridge_width 0.5)
				(island_removal_mode 0)
			)
			(polygon
				(pts
					(xy 17.78 -74.041) (xy 17.272 -74.041) (xy 17.272 -73.66) (xy 17.78 -73.66)
				)
			)
		)
		(zone
			(layer "B.Cu")
			(hatch none 0.5)
			(connect_pads
				(clearance 0)
			)
			(min_thickness 0.25)
			(keepout
				(tracks allowed)
				(vias not_allowed)
				(pads allowed)
				(copperpour not_allowed)
				(footprints allowed)
			)
			(placement
				(enabled no)
				(sheetname "")
			)
			(fill
				(thermal_gap 0.5)
				(thermal_bridge_width 0.5)
				(island_removal_mode 0)
			)
			(polygon
				(pts
					(xy 17.78 -74.041) (xy 17.272 -74.041) (xy 17.272 -73.66) (xy 17.78 -73.66)
				)
			)
		)
	)
	(footprint ""
		(layer "B.Cu")
		(at 476.25 -147.193 -90)
		(property "Reference" "R6W16"
			(at 0.8382 -0.67818 270)
			(unlocked yes)
			(layer "B.SilkS")
			(effects
				(font
					(size 0.4064 0.254)
					(thickness 0.1524)
				)
				(justify left mirror)
			)
		)
		(property "Value" ""
			(at 0 0 90)
			(layer "B.Fab")
			(effects
				(font
					(size 1.27 1.27)
				)
				(justify mirror)
			)
		)
		(duplicate_pad_numbers_are_jumpers no)
		(fp_poly
			(pts
				(xy 0.2794 -0.1016) (xy -0.2794 -0.1016) (xy -0.2794 0.9906) (xy 0.2794 0.9906)
			)
			(stroke
				(width 0)
				(type default)
			)
			(fill no)
			(layer "B.CrtYd")
		)
		(fp_line
			(start -0.2794 0.9906)
			(end -0.2794 -0.1016)
			(stroke
				(width 0.1)
				(type default)
			)
			(layer "B.Fab")
		)
		(fp_line
			(start 0.2794 0.9906)
			(end -0.2794 0.9906)
			(stroke
				(width 0.1)
				(type default)
			)
			(layer "B.Fab")
		)
		(fp_line
			(start -0.2794 -0.1016)
			(end 0.2794 -0.1016)
			(stroke
				(width 0.1)
				(type default)
			)
			(layer "B.Fab")
		)
		(fp_line
			(start 0.2794 -0.1016)
			(end 0.2794 0.9906)
			(stroke
				(width 0.1)
				(type default)
			)
			(layer "B.Fab")
		)
		(pad "1" smd rect
			(at 0 0 90)
			(size 0.508 0.508)
			(layers "B.Cu" "B.Mask" "B.Paste")
			(net "P3V3_STBY")
		)
		(pad "2" smd rect
			(at 0 0.889 90)
			(size 0.508 0.508)
			(layers "B.Cu" "B.Mask" "B.Paste")
			(net "FM_SOL_UART_CH_SEL")
		)
		(zone
			(layer "B.Cu")
			(hatch none 0.5)
			(connect_pads
				(clearance 0)
			)
			(min_thickness 0.25)
			(keepout
				(tracks not_allowed)
				(vias allowed)
				(pads allowed)
				(copperpour not_allowed)
				(footprints allowed)
			)
			(placement
				(enabled no)
				(sheetname "")
			)
			(fill
				(thermal_gap 0.5)
				(thermal_bridge_width 0.5)
				(island_removal_mode 0)
			)
			(polygon
				(pts
					(xy 475.615 -146.939) (xy 475.615 -147.447) (xy 475.996 -147.447) (xy 475.996 -146.939)
				)
			)
		)
		(zone
			(layer "B.Cu")
			(hatch none 0.5)
			(connect_pads
				(clearance 0)
			)
			(min_thickness 0.25)
			(keepout
				(tracks allowed)
				(vias not_allowed)
				(pads allowed)
				(copperpour not_allowed)
				(footprints allowed)
			)
			(placement
				(enabled no)
				(sheetname "")
			)
			(fill
				(thermal_gap 0.5)
				(thermal_bridge_width 0.5)
				(island_removal_mode 0)
			)
			(polygon
				(pts
					(xy 475.996 -146.939) (xy 475.996 -147.447) (xy 475.615 -147.447) (xy 475.615 -146.939)
				)
			)
		)
	)
	(footprint ""
		(layer "B.Cu")
		(at 104.394254 -85.06714)
		(property "Reference" "C8P4"
			(at 0 0 0)
			(layer "B.SilkS")
			(hide yes)
			(effects
				(font
					(size 1.27 1.27)
				)
				(justify mirror)
			)
		)
		(property "Value" ""
			(at 0 0 0)
			(layer "B.Fab")
			(effects
				(font
					(size 1.27 1.27)
				)
				(justify mirror)
			)
		)
		(duplicate_pad_numbers_are_jumpers no)
		(fp_poly
			(pts
				(xy 0.7239 -0.2159) (xy -0.7239 -0.2159) (xy -0.7239 1.9939) (xy 0.7239 1.9939)
			)
			(stroke
				(width 0)
				(type default)
			)
			(fill no)
			(layer "B.CrtYd")
		)
		(fp_line
			(start -0.7239 -0.2159)
			(end 0.7239 -0.2159)
			(stroke
				(width 0.1)
				(type default)
			)
			(layer "B.Fab")
		)
		(fp_line
			(start -0.7239 1.9939)
			(end -0.7239 -0.2159)
			(stroke
				(width 0.1)
				(type default)
			)
			(layer "B.Fab")
		)
		(fp_line
			(start 0.7239 -0.2159)
			(end 0.7239 1.9939)
			(stroke
				(width 0.1)
				(type default)
			)
			(layer "B.Fab")
		)
		(fp_line
			(start 0.7239 1.9939)
			(end -0.7239 1.9939)
			(stroke
				(width 0.1)
				(type default)
			)
			(layer "B.Fab")
		)
		(pad "1" smd rect
			(at 0 0 180)
			(size 1.27 1.016)
			(layers "B.Cu" "B.Mask" "B.Paste")
			(net "PVDDQ_KLM")
		)
		(pad "2" smd rect
			(at 0 1.778 180)
			(size 1.27 1.016)
			(layers "B.Cu" "B.Mask" "B.Paste")
			(net "GND")
		)
		(zone
			(layer "B.Cu")
			(hatch none 0.5)
			(connect_pads
				(clearance 0)
			)
			(min_thickness 0.25)
			(keepout
				(tracks not_allowed)
				(vias allowed)
				(pads allowed)
				(copperpour not_allowed)
				(footprints allowed)
			)
			(placement
				(enabled no)
				(sheetname "")
			)
			(fill
				(thermal_gap 0.5)
				(thermal_bridge_width 0.5)
				(island_removal_mode 0)
			)
			(polygon
				(pts
					(xy 105.029254 -84.55914) (xy 103.759254 -84.55914) (xy 103.759254 -83.79714) (xy 105.029254 -83.79714)
				)
			)
		)
	)
)
